(kicad_pcb
	(version 20260206)
	(generator "pcbnew")
	(generator_version "10.0")
	(general
		(thickness 1.6)
		(legacy_teardrops no)
	)
	(paper "A4")
	(title_block
		(title "Bryce Canyon_IOM_IOC_16318-2_OCP.brd")
		(comment 1 "Bryce Canyon / footprints 472-477 of 1605")
	)
	(layers
		(0 "F.Cu" signal "TOP")
		(4 "In1.Cu" signal "L2GND")
		(6 "In2.Cu" signal "L3")
		(8 "In3.Cu" signal "L4VCC")
		(10 "In4.Cu" signal "L5VCC")
		(12 "In5.Cu" signal "L6")
		(14 "In6.Cu" signal "L7GND")
		(2 "B.Cu" signal "BOTTOM")
		(9 "F.Adhes" user "F.Adhesive")
		(11 "B.Adhes" user "B.Adhesive")
		(13 "F.Paste" user "Package Geometry/Pastemask Top")
		(15 "B.Paste" user "Package Geometry/Pastemask Bottom")
		(5 "F.SilkS" user "Ref Des/Silkscreen Top")
		(7 "B.SilkS" user "Ref Des/Silkscreen Bottom")
		(1 "F.Mask" user "Board Geometry/Soldermask Top")
		(3 "B.Mask" user "Board Geometry/Soldermask Bottom")
		(17 "Dwgs.User" user "User.Drawings")
		(19 "Cmts.User" user "User.Comments")
		(21 "Eco1.User" user "User.Eco1")
		(23 "Eco2.User" user "User.Eco2")
		(25 "Edge.Cuts" user "Board Geometry/Outline")
		(27 "Margin" user)
		(31 "F.CrtYd" user "Package Geometry/Place Bound Top")
		(29 "B.CrtYd" user "Package Geometry/Place Bound Bottom")
		(35 "F.Fab" user "Ref Des/Assembly Top")
		(33 "B.Fab" user "Ref Des/Assembly Bottom")
	)
	(footprint ""
		(layer "F.Cu")
		(at 68.4022 -153.797 -90)
		(property "Reference" "R306"
			(at 0 0 270)
			(layer "F.SilkS")
			(hide yes)
			(effects
				(font
					(size 1.27 1.27)
				)
			)
		)
		(property "Value" "33R2J-2-GP"
			(at 0.064008 -3.993896 270)
			(unlocked yes)
			(layer "F.Fab")
			(hide yes)
			(effects
				(font
					(size 1.016 1.016)
					(thickness 0.1524)
				)
			)
		)
		(property "Device Type" "R402H16"
			(at 0.064008 -5.517896 270)
			(unlocked yes)
			(layer "F.Fab")
			(hide yes)
			(effects
				(font
					(size 1.016 1.016)
					(thickness 0.1524)
				)
			)
		)
		(duplicate_pad_numbers_are_jumpers no)
		(fp_line
			(start -0.508 -0.9398)
			(end -0.508 0.9398)
			(stroke
				(width 0.1524)
				(type default)
			)
			(layer "F.SilkS")
		)
		(fp_line
			(start 0.508 -0.9398)
			(end -0.508 -0.9398)
			(stroke
				(width 0.1524)
				(type default)
			)
			(layer "F.SilkS")
		)
		(fp_rect
			(start -0.508 0.9398)
			(end 0.508 -0.9398)
			(stroke
				(width 0)
				(type default)
			)
			(fill no)
			(layer "F.CrtYd")
		)
		(fp_rect
			(start -0.508 0.9398)
			(end 0.508 -0.9398)
			(stroke
				(width 0)
				(type default)
			)
			(fill no)
			(layer "F.Fab")
		)
		(pad "1" smd custom
			(at 0 -0.4445 270)
			(size 0.1397 0.1397)
			(layers "F.Cu" "F.Mask" "F.Paste")
			(net "50M_CLK_OUT")
			(options
				(clearance outline)
				(anchor circle)
			)
			(primitives
				(gr_poly
					(pts
						(arc
							(start -0.1778 -0.2794)
							(mid -0.249642 -0.249642)
							(end -0.2794 -0.1778)
						)
						(arc
							(start -0.2794 0.1778)
							(mid -0.249642 0.249642)
							(end -0.1778 0.2794)
						)
						(arc
							(start 0.1778 0.2794)
							(mid 0.249642 0.249642)
							(end 0.2794 0.1778)
						)
						(arc
							(start 0.2794 -0.1778)
							(mid 0.249642 -0.249642)
							(end 0.1778 -0.2794)
						)
					)
					(width 0)
					(fill yes)
				)
			)
		)
		(pad "2" smd custom
			(at 0 0.4445 270)
			(size 0.1397 0.1397)
			(layers "F.Cu" "F.Mask" "F.Paste")
			(net "50M_CLK_OUT_R")
			(options
				(clearance outline)
				(anchor circle)
			)
			(primitives
				(gr_poly
					(pts
						(arc
							(start -0.1778 -0.2794)
							(mid -0.249642 -0.249642)
							(end -0.2794 -0.1778)
						)
						(arc
							(start -0.2794 0.1778)
							(mid -0.249642 0.249642)
							(end -0.1778 0.2794)
						)
						(arc
							(start 0.1778 0.2794)
							(mid 0.249642 0.249642)
							(end 0.2794 0.1778)
						)
						(arc
							(start 0.2794 -0.1778)
							(mid 0.249642 -0.249642)
							(end 0.1778 -0.2794)
						)
					)
					(width 0)
					(fill yes)
				)
			)
		)
	)
	(footprint ""
		(layer "F.Cu")
		(at 66.929 -165.735 -90)
		(property "Reference" "Q2"
			(at 0 0 270)
			(layer "F.SilkS")
			(hide yes)
			(effects
				(font
					(size 1.27 1.27)
				)
			)
		)
		(property "Value" "MMBT3904-3-GP"
			(at 0.10287 -10.29843 270)
			(unlocked yes)
			(layer "F.Fab")
			(hide yes)
			(effects
				(font
					(size 1.016 1.016)
					(thickness 0.1524)
				)
			)
		)
		(property "Device Type" "SOT23CBE2D4H44"
			(at 0.10287 -12.20343 270)
			(unlocked yes)
			(layer "F.Fab")
			(hide yes)
			(effects
				(font
					(size 1.016 1.016)
					(thickness 0.1524)
				)
			)
		)
		(duplicate_pad_numbers_are_jumpers no)
		(fp_line
			(start -1.651 1.778)
			(end 1.651 1.778)
			(stroke
				(width 0.1524)
				(type default)
			)
			(layer "F.SilkS")
		)
		(fp_line
			(start 1.651 1.778)
			(end 1.651 -1.778)
			(stroke
				(width 0.1524)
				(type default)
			)
			(layer "F.SilkS")
		)
		(fp_line
			(start -1.651 -1.778)
			(end -1.651 1.778)
			(stroke
				(width 0.1524)
				(type default)
			)
			(layer "F.SilkS")
		)
		(fp_line
			(start 1.651 -1.778)
			(end -1.651 -1.778)
			(stroke
				(width 0.1524)
				(type default)
			)
			(layer "F.SilkS")
		)
		(fp_poly
			(pts
				(xy -1.778 1.8796) (xy -1.778 -1.8796) (xy 1.778 -1.8796) (xy 1.778 1.8796)
			)
			(stroke
				(width 0)
				(type default)
			)
			(fill no)
			(layer "F.CrtYd")
		)
		(fp_poly
			(pts
				(xy -1.778 1.8796) (xy -1.778 -1.8796) (xy 1.778 -1.8796) (xy 1.778 1.8796)
			)
			(stroke
				(width 0)
				(type default)
			)
			(fill no)
			(layer "F.Fab")
		)
		(pad "B" smd custom
			(at -0.98425 0.9525 270)
			(size 0.1905 0.1905)
			(layers "F.Cu" "F.Mask" "F.Paste")
			(net "FM_TPM_PRSNT_RST")
			(options
				(clearance outline)
				(anchor circle)
			)
			(primitives
				(gr_poly
					(pts
						(arc
							(start -0.1778 0.5715)
							(mid -0.321484 0.511984)
							(end -0.381 0.3683)
						)
						(arc
							(start -0.381 -0.3683)
							(mid -0.321484 -0.511984)
							(end -0.1778 -0.5715)
						)
						(arc
							(start 0.1778 -0.5715)
							(mid 0.321484 -0.511984)
							(end 0.381 -0.3683)
						)
						(arc
							(start 0.381 0.3683)
							(mid 0.321484 0.511984)
							(end 0.1778 0.5715)
						)
					)
					(width 0)
					(fill yes)
				)
			)
		)
		(pad "C" smd custom
			(at 0 -0.9525 270)
			(size 0.1905 0.1905)
			(layers "F.Cu" "F.Mask" "F.Paste")
			(net "BMC_TPM_RST_N")
			(options
				(clearance outline)
				(anchor circle)
			)
			(primitives
				(gr_poly
					(pts
						(arc
							(start -0.1778 0.5715)
							(mid -0.321484 0.511984)
							(end -0.381 0.3683)
						)
						(arc
							(start -0.381 -0.3683)
							(mid -0.321484 -0.511984)
							(end -0.1778 -0.5715)
						)
						(arc
							(start 0.1778 -0.5715)
							(mid 0.321484 -0.511984)
							(end 0.381 -0.3683)
						)
						(arc
							(start 0.381 0.3683)
							(mid 0.321484 0.511984)
							(end 0.1778 0.5715)
						)
					)
					(width 0)
					(fill yes)
				)
			)
		)
		(pad "E" smd custom
			(at 0.98425 0.9525 270)
			(size 0.1905 0.1905)
			(layers "F.Cu" "F.Mask" "F.Paste")
			(net "GND")
			(options
				(clearance outline)
				(anchor circle)
			)
			(primitives
				(gr_poly
					(pts
						(arc
							(start -0.1778 0.5715)
							(mid -0.321484 0.511984)
							(end -0.381 0.3683)
						)
						(arc
							(start -0.381 -0.3683)
							(mid -0.321484 -0.511984)
							(end -0.1778 -0.5715)
						)
						(arc
							(start 0.1778 -0.5715)
							(mid 0.321484 -0.511984)
							(end 0.381 -0.3683)
						)
						(arc
							(start 0.381 0.3683)
							(mid 0.321484 0.511984)
							(end 0.1778 0.5715)
						)
					)
					(width 0)
					(fill yes)
				)
			)
		)
	)
	(footprint ""
		(layer "F.Cu")
		(at 63.126874 -175.139096)
		(property "Reference" "U9"
			(at 0 0 0)
			(layer "F.SilkS")
			(hide yes)
			(effects
				(font
					(size 1.27 1.27)
				)
			)
		)
		(property "Value" "SN74LVC1G07DCKRG4-2-GP"
			(at -2.3368 -8.6868 0)
			(unlocked yes)
			(layer "F.Fab")
			(hide yes)
			(effects
				(font
					(size 1.016 1.016)
					(thickness 0.1524)
				)
			)
		)
		(property "Device Type" "SC70-5H44"
			(at -2.3114 -10.414 0)
			(unlocked yes)
			(layer "F.Fab")
			(hide yes)
			(effects
				(font
					(size 1.016 1.016)
					(thickness 0.1524)
				)
			)
		)
		(duplicate_pad_numbers_are_jumpers no)
		(fp_line
			(start -1.27 -1.7018)
			(end 1.27 -1.7018)
			(stroke
				(width 0.1524)
				(type default)
			)
			(layer "F.SilkS")
		)
		(fp_line
			(start -1.27 1.7018)
			(end -1.27 -1.7018)
			(stroke
				(width 0.1524)
				(type default)
			)
			(layer "F.SilkS")
		)
		(fp_line
			(start 0.6604 -1.8034)
			(end 1.3843 -1.8034)
			(stroke
				(width 0.3302)
				(type default)
			)
			(layer "F.SilkS")
		)
		(fp_line
			(start 1.27 -1.7018)
			(end 1.27 1.7018)
			(stroke
				(width 0.1524)
				(type default)
			)
			(layer "F.SilkS")
		)
		(fp_line
			(start 1.27 1.7018)
			(end -1.27 1.7018)
			(stroke
				(width 0.1524)
				(type default)
			)
			(layer "F.SilkS")
		)
		(fp_line
			(start 1.3843 -1.8034)
			(end 1.3843 -1.1176)
			(stroke
				(width 0.3302)
				(type default)
			)
			(layer "F.SilkS")
		)
		(fp_rect
			(start -1.524 1.9558)
			(end 1.524 -1.9558)
			(stroke
				(width 0)
				(type default)
			)
			(fill no)
			(layer "F.CrtYd")
		)
		(fp_poly
			(pts
				(xy -1.524 -1.9558) (xy 1.524 -1.9558) (xy 1.524 1.9558) (xy -1.524 1.9558)
			)
			(stroke
				(width 0)
				(type default)
			)
			(fill no)
			(layer "F.Fab")
		)
		(pad "1" smd rect
			(at 0.65024 -0.8255)
			(size 0.4064 1.2192)
			(layers "F.Cu" "F.Mask" "F.Paste")
			(net "Net_312")
		)
		(pad "2" smd rect
			(at 0 -0.8255)
			(size 0.4064 1.2192)
			(layers "F.Cu" "F.Mask" "F.Paste")
			(net "FM_BMC_RESET_N")
		)
		(pad "3" smd rect
			(at -0.65024 -0.8255)
			(size 0.4064 1.2192)
			(layers "F.Cu" "F.Mask" "F.Paste")
			(net "GND")
		)
		(pad "4" smd rect
			(at -0.65024 0.8255)
			(size 0.4064 1.2192)
			(layers "F.Cu" "F.Mask" "F.Paste")
			(net "FM_TPM_PRSNT_RST_N_C")
		)
		(pad "5" smd rect
			(at 0.65024 0.8255)
			(size 0.4064 1.2192)
			(layers "F.Cu" "F.Mask" "F.Paste")
			(net "P3V3_STBY")
		)
	)
	(footprint ""
		(layer "F.Cu")
		(at 63.2841 -146.8882 90)
		(property "Reference" "R190"
			(at 0 0 90)
			(layer "F.SilkS")
			(hide yes)
			(effects
				(font
					(size 1.27 1.27)
				)
			)
		)
		(property "Value" "499R2F-2-GP"
			(at 0.064008 -3.993896 90)
			(unlocked yes)
			(layer "F.Fab")
			(hide yes)
			(effects
				(font
					(size 1.016 1.016)
					(thickness 0.1524)
				)
			)
		)
		(property "Device Type" "R402H16"
			(at 0.064008 -5.517896 90)
			(unlocked yes)
			(layer "F.Fab")
			(hide yes)
			(effects
				(font
					(size 1.016 1.016)
					(thickness 0.1524)
				)
			)
		)
		(duplicate_pad_numbers_are_jumpers no)
		(fp_line
			(start 0.508 -0.9398)
			(end -0.508 -0.9398)
			(stroke
				(width 0.1524)
				(type default)
			)
			(layer "F.SilkS")
		)
		(fp_line
			(start -0.508 -0.9398)
			(end -0.508 0.9398)
			(stroke
				(width 0.1524)
				(type default)
			)
			(layer "F.SilkS")
		)
		(fp_rect
			(start -0.508 0.9398)
			(end 0.508 -0.9398)
			(stroke
				(width 0)
				(type default)
			)
			(fill no)
			(layer "F.CrtYd")
		)
		(fp_rect
			(start -0.508 0.9398)
			(end 0.508 -0.9398)
			(stroke
				(width 0)
				(type default)
			)
			(fill no)
			(layer "F.Fab")
		)
		(pad "1" smd custom
			(at 0 -0.4445 90)
			(size 0.1397 0.1397)
			(layers "F.Cu" "F.Mask" "F.Paste")
			(net "I2C_BMC_COMP_SDA_OUT")
			(options
				(clearance outline)
				(anchor circle)
			)
			(primitives
				(gr_poly
					(pts
						(arc
							(start -0.1778 -0.2794)
							(mid -0.249642 -0.249642)
							(end -0.2794 -0.1778)
						)
						(arc
							(start -0.2794 0.1778)
							(mid -0.249642 0.249642)
							(end -0.1778 0.2794)
						)
						(arc
							(start 0.1778 0.2794)
							(mid 0.249642 0.249642)
							(end 0.2794 0.1778)
						)
						(arc
							(start 0.2794 -0.1778)
							(mid 0.249642 -0.249642)
							(end 0.1778 -0.2794)
						)
					)
					(width 0)
					(fill yes)
				)
			)
		)
		(pad "2" smd custom
			(at 0 0.4445 90)
			(size 0.1397 0.1397)
			(layers "F.Cu" "F.Mask" "F.Paste")
			(net "P3V3_STBY")
			(options
				(clearance outline)
				(anchor circle)
			)
			(primitives
				(gr_poly
					(pts
						(arc
							(start -0.1778 -0.2794)
							(mid -0.249642 -0.249642)
							(end -0.2794 -0.1778)
						)
						(arc
							(start -0.2794 0.1778)
							(mid -0.249642 0.249642)
							(end -0.1778 0.2794)
						)
						(arc
							(start 0.1778 0.2794)
							(mid 0.249642 0.249642)
							(end 0.2794 0.1778)
						)
						(arc
							(start 0.2794 -0.1778)
							(mid 0.249642 -0.249642)
							(end 0.1778 -0.2794)
						)
					)
					(width 0)
					(fill yes)
				)
			)
		)
	)
	(footprint ""
		(layer "F.Cu")
		(at 94.810072 -13.671042 90)
		(property "Reference" "D15"
			(at 0 0 90)
			(layer "F.SilkS")
			(hide yes)
			(effects
				(font
					(size 1.27 1.27)
				)
			)
		)
		(property "Value" "PESD5V0S1BL-1-GP"
			(at 1.8923 -1.5621 90)
			(unlocked yes)
			(layer "F.Fab")
			(hide yes)
			(effects
				(font
					(size 1.016 1.016)
					(thickness 0.1524)
				)
			)
		)
		(property "Device Type" "SOD882-10D6-1H20"
			(at 1.8923 -3.0861 90)
			(unlocked yes)
			(layer "F.Fab")
			(hide yes)
			(effects
				(font
					(size 1.016 1.016)
					(thickness 0.1524)
				)
			)
		)
		(duplicate_pad_numbers_are_jumpers no)
		(fp_line
			(start -0.3048 -0.9271)
			(end 0.3048 -0.9271)
			(stroke
				(width 0.254)
				(type default)
			)
			(layer "F.SilkS")
		)
		(fp_rect
			(start -0.2921 0.4953)
			(end 0.2921 -0.4953)
			(stroke
				(width 0)
				(type default)
			)
			(fill no)
			(layer "F.CrtYd")
		)
		(fp_poly
			(pts
				(xy -0.4318 0.8001) (xy -0.4318 -0.266192) (xy -0.2921 -0.266192) (xy -0.2921 0.4953) (xy 0.2921 0.4953)
				(xy 0.2921 -0.4953) (xy -0.2921 -0.4953) (xy -0.2921 -0.2667) (xy -0.4318 -0.2667) (xy -0.4318 -0.8001)
				(xy 0.4318 -0.8001) (xy 0.4318 0.8001)
			)
			(stroke
				(width 0)
				(type default)
			)
			(fill no)
			(layer "F.CrtYd")
		)
		(fp_rect
			(start -0.4318 0.8001)
			(end 0.4318 -0.8001)
			(stroke
				(width 0)
				(type default)
			)
			(fill no)
			(layer "F.Fab")
		)
		(pad "1" smd custom
			(at 0 -0.4445 90)
			(size 0.1143 0.1143)
			(layers "F.Cu" "F.Mask" "F.Paste")
			(net "I2C_DEBUG_SDA")
			(options
				(clearance outline)
				(anchor circle)
			)
			(primitives
				(gr_poly
					(pts
						(arc
							(start -0.2032 0.2286)
							(mid -0.275042 0.198842)
							(end -0.3048 0.127)
						)
						(arc
							(start -0.3048 -0.127)
							(mid -0.275042 -0.198842)
							(end -0.2032 -0.2286)
						)
						(arc
							(start 0.2032 -0.2286)
							(mid 0.275042 -0.198842)
							(end 0.3048 -0.127)
						)
						(arc
							(start 0.3048 0.127)
							(mid 0.275042 0.198842)
							(end 0.2032 0.2286)
						)
					)
					(width 0)
					(fill yes)
				)
			)
		)
		(pad "2" smd custom
			(at 0 0.4445 90)
			(size 0.1143 0.1143)
			(layers "F.Cu" "F.Mask" "F.Paste")
			(net "GND")
			(options
				(clearance outline)
				(anchor circle)
			)
			(primitives
				(gr_poly
					(pts
						(arc
							(start 0.2032 -0.2286)
							(mid 0.275042 -0.198842)
							(end 0.3048 -0.127)
						)
						(arc
							(start 0.3048 0.127)
							(mid 0.275042 0.198842)
							(end 0.2032 0.2286)
						)
						(arc
							(start -0.2032 0.2286)
							(mid -0.275042 0.198842)
							(end -0.3048 0.127)
						)
						(arc
							(start -0.3048 -0.127)
							(mid -0.275042 -0.198842)
							(end -0.2032 -0.2286)
						)
					)
					(width 0)
					(fill yes)
				)
			)
		)
	)
	(footprint ""
		(layer "F.Cu")
		(at 53.773324 -162.481768 180)
		(property "Reference" "R412"
			(at 0 0 180)
			(layer "F.SilkS")
			(hide yes)
			(effects
				(font
					(size 1.27 1.27)
				)
			)
		)
		(property "Value" "1KR2F-3-GP"
			(at 0.064008 -3.993896 180)
			(unlocked yes)
			(layer "F.Fab")
			(hide yes)
			(effects
				(font
					(size 1.016 1.016)
					(thickness 0.1524)
				)
			)
		)
		(property "Device Type" "R402H16"
			(at 0.064008 -5.517896 180)
			(unlocked yes)
			(layer "F.Fab")
			(hide yes)
			(effects
				(font
					(size 1.016 1.016)
					(thickness 0.1524)
				)
			)
		)
		(duplicate_pad_numbers_are_jumpers no)
		(fp_line
			(start 0.508 -0.9398)
			(end -0.508 -0.9398)
			(stroke
				(width 0.1524)
				(type default)
			)
			(layer "F.SilkS")
		)
		(fp_line
			(start -0.508 -0.9398)
			(end -0.508 0.9398)
			(stroke
				(width 0.1524)
				(type default)
			)
			(layer "F.SilkS")
		)
		(fp_rect
			(start -0.508 0.9398)
			(end 0.508 -0.9398)
			(stroke
				(width 0)
				(type default)
			)
			(fill no)
			(layer "F.CrtYd")
		)
		(fp_rect
			(start -0.508 0.9398)
			(end 0.508 -0.9398)
			(stroke
				(width 0)
				(type default)
			)
			(fill no)
			(layer "F.Fab")
		)
		(pad "1" smd custom
			(at 0 -0.4445 180)
			(size 0.1397 0.1397)
			(layers "F.Cu" "F.Mask" "F.Paste")
			(net "ADC_P3V3")
			(options
				(clearance outline)
				(anchor circle)
			)
			(primitives
				(gr_poly
					(pts
						(arc
							(start -0.1778 -0.2794)
							(mid -0.249642 -0.249642)
							(end -0.2794 -0.1778)
						)
						(arc
							(start -0.2794 0.1778)
							(mid -0.249642 0.249642)
							(end -0.1778 0.2794)
						)
						(arc
							(start 0.1778 0.2794)
							(mid 0.249642 0.249642)
							(end 0.2794 0.1778)
						)
						(arc
							(start 0.2794 -0.1778)
							(mid 0.249642 -0.249642)
							(end 0.1778 -0.2794)
						)
					)
					(width 0)
					(fill yes)
				)
			)
		)
		(pad "2" smd custom
			(at 0 0.4445 180)
			(size 0.1397 0.1397)
			(layers "F.Cu" "F.Mask" "F.Paste")
			(net "GND")
			(options
				(clearance outline)
				(anchor circle)
			)
			(primitives
				(gr_poly
					(pts
						(arc
							(start -0.1778 -0.2794)
							(mid -0.249642 -0.249642)
							(end -0.2794 -0.1778)
						)
						(arc
							(start -0.2794 0.1778)
							(mid -0.249642 0.249642)
							(end -0.1778 0.2794)
						)
						(arc
							(start 0.1778 0.2794)
							(mid 0.249642 0.249642)
							(end 0.2794 0.1778)
						)
						(arc
							(start 0.2794 -0.1778)
							(mid 0.249642 -0.249642)
							(end 0.1778 -0.2794)
						)
					)
					(width 0)
					(fill yes)
				)
			)
		)
	)
)
